(kicad_pcb
	(version 20241229)
	(generator "pcbnew")
	(generator_version "9.0")
	(general
		(thickness 1.62)
		(legacy_teardrops no)
	)
	(paper "A3")
	(title_block
		(title "COM Express 7 Baseboard")
		(date "2025-02-04")
		(rev "1.1.2")
		(company "Antmicro Ltd")
		(comment 1 "www.antmicro.com")
		(comment 9 "footprint 631 of 802 (U39), pads 43-57 of 57")
	)
	(layers
		(0 "F.Cu" signal)
		(4 "In1.Cu" signal)
		(6 "In2.Cu" signal)
		(8 "In3.Cu" signal)
		(10 "In4.Cu" signal)
		(12 "In5.Cu" signal)
		(14 "In6.Cu" signal)
		(2 "B.Cu" signal)
		(9 "F.Adhes" user "F.Adhesive")
		(11 "B.Adhes" user "B.Adhesive")
		(13 "F.Paste" user)
		(15 "B.Paste" user)
		(5 "F.SilkS" user "F.Silkscreen")
		(7 "B.SilkS" user "B.Silkscreen")
		(1 "F.Mask" user)
		(3 "B.Mask" user)
		(17 "Dwgs.User" user "User.Drawings")
		(19 "Cmts.User" user "User.Comments")
		(21 "Eco1.User" user "User.Eco1")
		(23 "Eco2.User" user "User.Eco2")
		(25 "Edge.Cuts" user)
		(27 "Margin" user)
		(31 "F.CrtYd" user "F.Courtyard")
		(29 "B.CrtYd" user "B.Courtyard")
		(35 "F.Fab" user)
		(33 "B.Fab" user)
	)
	(footprint "antmicro-footprints:WQFN-42-1EP_3.5x9mm_P0.5mm"
		(layer "B.Cu")
		(at 117.401 147.361 -90)
		(descr "WQFN, 42 Pin (http://www.ti.com/lit/ds/symlink/ts3l501e.pdf#page=23), generated with kicad-footprint-generator ipc_noLead_generator.py")
		(tags "WQFN NoLead")
		(property "Reference" "U39"
			(at -2.301 5.001 90)
			(layer "B.SilkS")
			(effects
				(font
					(size 0.7 0.7)
					(thickness 0.15)
				)
				(justify left bottom mirror)
			)
		)
		(property "Value" "PI3EQX16904GL"
			(at 0 -5.82 90)
			(layer "B.Fab")
			(effects
				(font
					(size 0.7 0.7)
					(thickness 0.15)
				)
				(justify left bottom mirror)
			)
		)
		(property "Datasheet" "https://www.diodes.com/part/view/PI3EQX16904GL"
			(at 0 0 270)
			(layer "F.Fab")
			(hide yes)
			(effects
				(font
					(size 1.27 1.27)
					(thickness 0.15)
				)
			)
		)
		(property "Author" "Antmicro"
			(at -29.96 264.762 0)
			(layer "B.Fab")
			(hide yes)
			(effects
				(font
					(size 1 1)
					(thickness 0.15)
				)
				(justify mirror)
			)
		)
		(property "License" "Apache-2.0"
			(at -29.96 264.762 0)
			(layer "B.Fab")
			(hide yes)
			(effects
				(font
					(size 1 1)
					(thickness 0.15)
				)
				(justify mirror)
			)
		)
		(property "MPN" "PI3EQX16904GLZHEX"
			(at -29.96 264.762 0)
			(layer "B.Fab")
			(hide yes)
			(effects
				(font
					(size 1 1)
					(thickness 0.15)
				)
				(justify mirror)
			)
		)
		(property "Manufacturer" "Diodes Incorporated"
			(at -29.96 264.762 0)
			(layer "B.Fab")
			(hide yes)
			(effects
				(font
					(size 1 1)
					(thickness 0.15)
				)
				(justify mirror)
			)
		)
		(sheetname "PCIe redriver")
		(sheetfile "pcie_redriver.kicad_sch")
		(attr smd)
		(pad "29" smd roundrect
			(at 1.687 -0.5 270)
			(size 0.875 0.25)
			(layers "B.Cu" "B.Mask" "B.Paste")
			(roundrect_rratio 0.25)
			(net 965 "/PCIe redriver/PCIe_{O}_C.TX1-")
			(pinfunction "A2TX+")
			(pintype "input")
			(teardrops
				(best_length_ratio 0.2)
				(max_length 1)
				(best_width_ratio 0.9)
				(max_width 2)
				(curved_edges yes)
				(filter_ratio 0.9)
				(enabled yes)
				(allow_two_segments yes)
				(prefer_zone_connections yes)
			)
		)
		(pad "30" smd roundrect
			(at 1.687 0 270)
			(size 0.875 0.25)
			(layers "B.Cu" "B.Mask" "B.Paste")
			(roundrect_rratio 0.25)
			(net 2 "+3V3")
			(pinfunction "VCC")
			(pintype "passive")
			(teardrops
				(best_length_ratio 0.2)
				(max_length 1)
				(best_width_ratio 0.9)
				(max_width 2)
				(curved_edges yes)
				(filter_ratio 0.9)
				(enabled yes)
				(allow_two_segments yes)
				(prefer_zone_connections yes)
			)
		)
		(pad "31" smd roundrect
			(at 1.687 0.5 270)
			(size 0.875 0.25)
			(layers "B.Cu" "B.Mask" "B.Paste")
			(roundrect_rratio 0.25)
			(net 961 "/PCIe redriver/PCIe_{O}_C.TX2+")
			(pinfunction "A1TX-")
			(pintype "output")
			(teardrops
				(best_length_ratio 0.2)
				(max_length 1)
				(best_width_ratio 0.9)
				(max_width 2)
				(curved_edges yes)
				(filter_ratio 0.9)
				(enabled yes)
				(allow_two_segments yes)
				(prefer_zone_connections yes)
			)
		)
		(pad "32" smd roundrect
			(at 1.687 1 270)
			(size 0.875 0.25)
			(layers "B.Cu" "B.Mask" "B.Paste")
			(roundrect_rratio 0.25)
			(net 964 "/PCIe redriver/PCIe_{O}_C.TX2-")
			(pinfunction "A1TX+")
			(pintype "input")
			(teardrops
				(best_length_ratio 0.2)
				(max_length 1)
				(best_width_ratio 0.9)
				(max_width 2)
				(curved_edges yes)
				(filter_ratio 0.9)
				(enabled yes)
				(allow_two_segments yes)
				(prefer_zone_connections yes)
			)
		)
		(pad "33" smd roundrect
			(at 1.687 1.5 270)
			(size 0.875 0.25)
			(layers "B.Cu" "B.Mask" "B.Paste")
			(roundrect_rratio 0.25)
			(net 2 "+3V3")
			(pinfunction "VCC")
			(pintype "passive")
			(teardrops
				(best_length_ratio 0.2)
				(max_length 1)
				(best_width_ratio 0.9)
				(max_width 2)
				(curved_edges yes)
				(filter_ratio 0.9)
				(enabled yes)
				(allow_two_segments yes)
				(prefer_zone_connections yes)
			)
		)
		(pad "34" smd roundrect
			(at 1.687 2 270)
			(size 0.875 0.25)
			(layers "B.Cu" "B.Mask" "B.Paste")
			(roundrect_rratio 0.25)
			(net 94 "/PCIe redriver/PCIe_{O}_C.TX3+")
			(pinfunction "A0TX-")
			(pintype "output")
			(teardrops
				(best_length_ratio 0.2)
				(max_length 1)
				(best_width_ratio 0.9)
				(max_width 2)
				(curved_edges yes)
				(filter_ratio 0.9)
				(enabled yes)
				(allow_two_segments yes)
				(prefer_zone_connections yes)
			)
		)
		(pad "35" smd roundrect
			(at 1.687 2.5 270)
			(size 0.875 0.25)
			(layers "B.Cu" "B.Mask" "B.Paste")
			(roundrect_rratio 0.25)
			(net 99 "/PCIe redriver/PCIe_{O}_C.TX3-")
			(pinfunction "A0TX+")
			(pintype "input")
			(teardrops
				(best_length_ratio 0.2)
				(max_length 1)
				(best_width_ratio 0.9)
				(max_width 2)
				(curved_edges yes)
				(filter_ratio 0.9)
				(enabled yes)
				(allow_two_segments yes)
				(prefer_zone_connections yes)
			)
		)
		(pad "36" smd roundrect
			(at 1.687 3 270)
			(size 0.875 0.25)
			(layers "B.Cu" "B.Mask" "B.Paste")
			(roundrect_rratio 0.25)
			(net 2 "+3V3")
			(pinfunction "VCC")
			(pintype "passive")
			(teardrops
				(best_length_ratio 0.2)
				(max_length 1)
				(best_width_ratio 0.9)
				(max_width 2)
				(curved_edges yes)
				(filter_ratio 0.9)
				(enabled yes)
				(allow_two_segments yes)
				(prefer_zone_connections yes)
			)
		)
		(pad "37" smd roundrect
			(at 1.687 3.5 270)
			(size 0.875 0.25)
			(layers "B.Cu" "B.Mask" "B.Paste")
			(roundrect_rratio 0.25)
			(net 626 "/PCIe redriver/TX_FG0")
			(pinfunction "FG0")
			(pintype "passive")
			(teardrops
				(best_length_ratio 0.2)
				(max_length 1)
				(best_width_ratio 0.9)
				(max_width 2)
				(curved_edges yes)
				(filter_ratio 0.9)
				(enabled yes)
				(allow_two_segments yes)
				(prefer_zone_connections yes)
			)
		)
		(pad "38" smd roundrect
			(at 1.687 4 270)
			(size 0.875 0.25)
			(layers "B.Cu" "B.Mask" "B.Paste")
			(roundrect_rratio 0.25)
			(net 627 "/PCIe redriver/TX_FG1")
			(pinfunction "FG1")
			(pintype "passive")
			(teardrops
				(best_length_ratio 0.2)
				(max_length 1)
				(best_width_ratio 0.9)
				(max_width 2)
				(curved_edges yes)
				(filter_ratio 0.9)
				(enabled yes)
				(allow_two_segments yes)
				(prefer_zone_connections yes)
			)
		)
		(pad "39" smd roundrect
			(at 0.75 4.438 270)
			(size 0.25 0.875)
			(layers "B.Cu" "B.Mask" "B.Paste")
			(roundrect_rratio 0.25)
			(net 623 "/PCIe redriver/TX_EQ0")
			(pinfunction "EQ0")
			(pintype "passive")
			(teardrops
				(best_length_ratio 0.2)
				(max_length 1)
				(best_width_ratio 0.9)
				(max_width 2)
				(curved_edges yes)
				(filter_ratio 0.9)
				(enabled yes)
				(allow_two_segments yes)
				(prefer_zone_connections yes)
			)
		)
		(pad "40" smd roundrect
			(at 0.25 4.438 270)
			(size 0.25 0.875)
			(layers "B.Cu" "B.Mask" "B.Paste")
			(roundrect_rratio 0.25)
			(net 624 "/PCIe redriver/TX_EQ1")
			(pinfunction "EQ1")
			(pintype "passive")
			(teardrops
				(best_length_ratio 0.2)
				(max_length 1)
				(best_width_ratio 0.9)
				(max_width 2)
				(curved_edges yes)
				(filter_ratio 0.9)
				(enabled yes)
				(allow_two_segments yes)
				(prefer_zone_connections yes)
			)
		)
		(pad "41" smd roundrect
			(at -0.25 4.438 270)
			(size 0.25 0.875)
			(layers "B.Cu" "B.Mask" "B.Paste")
			(roundrect_rratio 0.25)
			(net 1 "GND")
			(pinfunction "AD2")
			(pintype "passive")
			(teardrops
				(best_length_ratio 0.2)
				(max_length 1)
				(best_width_ratio 0.9)
				(max_width 2)
				(curved_edges yes)
				(filter_ratio 0.9)
				(enabled no)
				(allow_two_segments yes)
				(prefer_zone_connections yes)
			)
		)
		(pad "42" smd roundrect
			(at -0.75 4.438 270)
			(size 0.25 0.875)
			(layers "B.Cu" "B.Mask" "B.Paste")
			(roundrect_rratio 0.25)
			(net 1 "GND")
			(pinfunction "AD3")
			(pintype "passive")
			(teardrops
				(best_length_ratio 0.2)
				(max_length 1)
				(best_width_ratio 0.9)
				(max_width 2)
				(curved_edges yes)
				(filter_ratio 0.9)
				(enabled no)
				(allow_two_segments yes)
				(prefer_zone_connections yes)
			)
		)
		(pad "43" smd rect
			(at 0 0 270)
			(size 2.05 7.55)
			(layers "B.Cu" "B.Mask")
			(net 1 "GND")
			(pinfunction "GND")
			(pintype "power_in")
			(teardrops
				(best_length_ratio 0.2)
				(max_length 1)
				(best_width_ratio 0.9)
				(max_width 2)
				(curved_edges yes)
				(filter_ratio 0.9)
				(enabled no)
				(allow_two_segments yes)
				(prefer_zone_connections yes)
			)
		)
	)
)
